(kicad_pcb
	(version 20260206)
	(generator "pcbnew")
	(generator_version "10.0")
	(general
		(thickness 1.6)
		(legacy_teardrops no)
	)
	(paper "A4")
	(title_block
		(title "01162023_DA0F0TEBIF0_F0T_Expander_BD_F_brd_V02_OCP.brd")
		(comment 1 "Grand Teton / footprints 2179-2185 of 9728")
	)
	(layers
		(0 "F.Cu" signal "TOP")
		(4 "In1.Cu" signal "GND")
		(6 "In2.Cu" signal "VCC")
		(8 "In3.Cu" signal "VCC1")
		(10 "In4.Cu" signal "GND1")
		(12 "In5.Cu" signal "IN1")
		(14 "In6.Cu" signal "GND2")
		(16 "In7.Cu" signal "IN2")
		(18 "In8.Cu" signal "GND3")
		(20 "In9.Cu" signal "IN3")
		(22 "In10.Cu" signal "GND4")
		(24 "In11.Cu" signal "IN4")
		(26 "In12.Cu" signal "GND5")
		(28 "In13.Cu" signal "IN5")
		(30 "In14.Cu" signal "GND6")
		(32 "In15.Cu" signal "IN6")
		(34 "In16.Cu" signal "GND7")
		(2 "B.Cu" signal "BOTTOM")
		(9 "F.Adhes" user "F.Adhesive")
		(11 "B.Adhes" user "B.Adhesive")
		(13 "F.Paste" user "Package Geometry/Pastemask Top")
		(15 "B.Paste" user "Package Geometry/Pastemask Bottom")
		(5 "F.SilkS" user "Ref Des/Silkscreen Top")
		(7 "B.SilkS" user "Ref Des/Silkscreen Bottom")
		(1 "F.Mask" user "Board Geometry/Soldermask Top")
		(3 "B.Mask" user "Board Geometry/Soldermask Bottom")
		(17 "Dwgs.User" user "User.Drawings")
		(19 "Cmts.User" user "User.Comments")
		(21 "Eco1.User" user "User.Eco1")
		(23 "Eco2.User" user "User.Eco2")
		(25 "Edge.Cuts" user "Board Geometry/Outline")
		(27 "Margin" user)
		(31 "F.CrtYd" user "Package Geometry/Place Bound Top")
		(29 "B.CrtYd" user "Package Geometry/Place Bound Bottom")
		(35 "F.Fab" user "Ref Des/Assembly Top")
		(33 "B.Fab" user "Ref Des/Assembly Bottom")
	)
	(footprint ""
		(layer "F.Cu")
		(at 179.777644 -115.283742 180)
		(property "Reference" "R190"
			(at 0 0 180)
			(layer "F.SilkS")
			(hide yes)
			(effects
				(font
					(size 1.27 1.27)
				)
			)
		)
		(property "Value" ""
			(at 0 0 180)
			(layer "F.Fab")
			(effects
				(font
					(size 1.27 1.27)
				)
			)
		)
		(duplicate_pad_numbers_are_jumpers no)
		(fp_line
			(start 0.7874 0.4064)
			(end -0.7874 0.4064)
			(stroke
				(width 0.1524)
				(type default)
			)
			(layer "F.SilkS")
		)
		(fp_line
			(start 0.7874 -0.4064)
			(end 0.7874 0.4064)
			(stroke
				(width 0.1524)
				(type default)
			)
			(layer "F.SilkS")
		)
		(fp_line
			(start -0.7874 0.4064)
			(end -0.7874 -0.4064)
			(stroke
				(width 0.1524)
				(type default)
			)
			(layer "F.SilkS")
		)
		(fp_line
			(start -0.7874 -0.4064)
			(end 0.7874 -0.4064)
			(stroke
				(width 0.1524)
				(type default)
			)
			(layer "F.SilkS")
		)
		(fp_line
			(start 0.67945 0.3048)
			(end 0.120396 0.3048)
			(stroke
				(width 0.1)
				(type default)
			)
			(layer "F.Fab")
		)
		(fp_line
			(start 0.67945 -0.3048)
			(end 0.67945 0.3048)
			(stroke
				(width 0.1)
				(type default)
			)
			(layer "F.Fab")
		)
		(fp_line
			(start 0.12065 -0.2794)
			(end 0.12065 -0.3048)
			(stroke
				(width 0.1)
				(type default)
			)
			(layer "F.Fab")
		)
		(fp_line
			(start 0.12065 -0.3048)
			(end 0.67945 -0.3048)
			(stroke
				(width 0.1)
				(type default)
			)
			(layer "F.Fab")
		)
		(fp_line
			(start 0.120396 0.3048)
			(end 0.120396 0.2794)
			(stroke
				(width 0.1)
				(type default)
			)
			(layer "F.Fab")
		)
		(fp_line
			(start 0.120396 0.2794)
			(end -0.12065 0.2794)
			(stroke
				(width 0.1)
				(type default)
			)
			(layer "F.Fab")
		)
		(fp_line
			(start -0.12065 0.3048)
			(end -0.67945 0.3048)
			(stroke
				(width 0.1)
				(type default)
			)
			(layer "F.Fab")
		)
		(fp_line
			(start -0.12065 0.2794)
			(end -0.12065 0.3048)
			(stroke
				(width 0.1)
				(type default)
			)
			(layer "F.Fab")
		)
		(fp_line
			(start -0.12065 -0.2794)
			(end 0.12065 -0.2794)
			(stroke
				(width 0.1)
				(type default)
			)
			(layer "F.Fab")
		)
		(fp_line
			(start -0.12065 -0.305054)
			(end -0.12065 -0.2794)
			(stroke
				(width 0.1)
				(type default)
			)
			(layer "F.Fab")
		)
		(fp_line
			(start -0.67945 0.3048)
			(end -0.67945 -0.305054)
			(stroke
				(width 0.1)
				(type default)
			)
			(layer "F.Fab")
		)
		(fp_line
			(start -0.67945 -0.305054)
			(end -0.12065 -0.305054)
			(stroke
				(width 0.1)
				(type default)
			)
			(layer "F.Fab")
		)
		(pad "1" smd circle
			(at -0.40005 0 180)
			(size 0 0)
			(layers "F.Cu" "F.Mask" "F.Paste")
			(net "RST_SMB_NIC3_MUX_ISO_R_N")
		)
		(pad "2" smd circle
			(at 0.40005 0 180)
			(size 0 0)
			(layers "F.Cu" "F.Mask" "F.Paste")
			(net "RST_SMB_NIC3_MUX_ISO_N")
		)
	)
	(footprint ""
		(layer "F.Cu")
		(at 303.671478 -25.342342 -90)
		(property "Reference" "R439"
			(at 0 0 270)
			(layer "F.SilkS")
			(hide yes)
			(effects
				(font
					(size 1.27 1.27)
				)
			)
		)
		(property "Value" ""
			(at 0 0 270)
			(layer "F.Fab")
			(effects
				(font
					(size 1.27 1.27)
				)
			)
		)
		(duplicate_pad_numbers_are_jumpers no)
		(fp_line
			(start -0.7874 0.4064)
			(end -0.7874 -0.4064)
			(stroke
				(width 0.1524)
				(type default)
			)
			(layer "F.SilkS")
		)
		(fp_line
			(start 0.7874 0.4064)
			(end -0.7874 0.4064)
			(stroke
				(width 0.1524)
				(type default)
			)
			(layer "F.SilkS")
		)
		(fp_line
			(start -0.7874 -0.4064)
			(end 0.7874 -0.4064)
			(stroke
				(width 0.1524)
				(type default)
			)
			(layer "F.SilkS")
		)
		(fp_line
			(start 0.7874 -0.4064)
			(end 0.7874 0.4064)
			(stroke
				(width 0.1524)
				(type default)
			)
			(layer "F.SilkS")
		)
		(fp_line
			(start -0.67945 0.3048)
			(end -0.67945 -0.305054)
			(stroke
				(width 0.1)
				(type default)
			)
			(layer "F.Fab")
		)
		(fp_line
			(start -0.12065 0.3048)
			(end -0.67945 0.3048)
			(stroke
				(width 0.1)
				(type default)
			)
			(layer "F.Fab")
		)
		(fp_line
			(start 0.120396 0.3048)
			(end 0.120396 0.2794)
			(stroke
				(width 0.1)
				(type default)
			)
			(layer "F.Fab")
		)
		(fp_line
			(start 0.67945 0.3048)
			(end 0.120396 0.3048)
			(stroke
				(width 0.1)
				(type default)
			)
			(layer "F.Fab")
		)
		(fp_line
			(start -0.12065 0.2794)
			(end -0.12065 0.3048)
			(stroke
				(width 0.1)
				(type default)
			)
			(layer "F.Fab")
		)
		(fp_line
			(start 0.120396 0.2794)
			(end -0.12065 0.2794)
			(stroke
				(width 0.1)
				(type default)
			)
			(layer "F.Fab")
		)
		(fp_line
			(start -0.12065 -0.2794)
			(end 0.12065 -0.2794)
			(stroke
				(width 0.1)
				(type default)
			)
			(layer "F.Fab")
		)
		(fp_line
			(start 0.12065 -0.2794)
			(end 0.12065 -0.3048)
			(stroke
				(width 0.1)
				(type default)
			)
			(layer "F.Fab")
		)
		(fp_line
			(start 0.12065 -0.3048)
			(end 0.67945 -0.3048)
			(stroke
				(width 0.1)
				(type default)
			)
			(layer "F.Fab")
		)
		(fp_line
			(start 0.67945 -0.3048)
			(end 0.67945 0.3048)
			(stroke
				(width 0.1)
				(type default)
			)
			(layer "F.Fab")
		)
		(fp_line
			(start -0.67945 -0.305054)
			(end -0.12065 -0.305054)
			(stroke
				(width 0.1)
				(type default)
			)
			(layer "F.Fab")
		)
		(fp_line
			(start -0.12065 -0.305054)
			(end -0.12065 -0.2794)
			(stroke
				(width 0.1)
				(type default)
			)
			(layer "F.Fab")
		)
		(pad "1" smd circle
			(at -0.40005 0 270)
			(size 0 0)
			(layers "F.Cu" "F.Mask" "F.Paste")
			(net "P3V3_SSD10")
		)
		(pad "2" smd circle
			(at 0.40005 0 270)
			(size 0 0)
			(layers "F.Cu" "F.Mask" "F.Paste")
			(net "DUALPORT_N_SSD10")
		)
	)
	(footprint ""
		(layer "F.Cu")
		(at 57.394094 -29.507688 -90)
		(property "Reference" "PC681"
			(at 0 0 270)
			(layer "F.SilkS")
			(hide yes)
			(effects
				(font
					(size 1.27 1.27)
				)
			)
		)
		(property "Value" ""
			(at 0 0 270)
			(layer "F.Fab")
			(effects
				(font
					(size 1.27 1.27)
				)
			)
		)
		(duplicate_pad_numbers_are_jumpers no)
		(fp_line
			(start -1.524 0.762)
			(end -1.524 -0.762)
			(stroke
				(width 0.1524)
				(type default)
			)
			(layer "F.SilkS")
		)
		(fp_line
			(start 1.524 0.762)
			(end -1.524 0.762)
			(stroke
				(width 0.1524)
				(type default)
			)
			(layer "F.SilkS")
		)
		(fp_line
			(start -1.524 -0.762)
			(end 1.524 -0.762)
			(stroke
				(width 0.1524)
				(type default)
			)
			(layer "F.SilkS")
		)
		(fp_line
			(start 1.524 -0.762)
			(end 1.524 0.762)
			(stroke
				(width 0.1524)
				(type default)
			)
			(layer "F.SilkS")
		)
		(fp_line
			(start -1.1049 0.724916)
			(end 1.1049 0.724916)
			(stroke
				(width 0.1)
				(type default)
			)
			(layer "F.Fab")
		)
		(fp_line
			(start 1.1049 0.724916)
			(end 1.1049 -0.724916)
			(stroke
				(width 0.1)
				(type default)
			)
			(layer "F.Fab")
		)
		(fp_line
			(start -1.1049 -0.724916)
			(end -1.1049 0.724916)
			(stroke
				(width 0.1)
				(type default)
			)
			(layer "F.Fab")
		)
		(fp_line
			(start 1.1049 -0.724916)
			(end -1.1049 -0.724916)
			(stroke
				(width 0.1)
				(type default)
			)
			(layer "F.Fab")
		)
		(pad "1" smd rect
			(at -0.889 0 90)
			(size 1.016 1.27)
			(layers "F.Cu" "F.Mask" "F.Paste")
			(net "P3V3_SSD2")
		)
		(pad "2" smd rect
			(at 0.889 0 90)
			(size 1.016 1.27)
			(layers "F.Cu" "F.Mask" "F.Paste")
			(net "GND")
		)
	)
	(footprint ""
		(layer "F.Cu")
		(at 103.15321 -366.507268)
		(property "Reference" "C4051"
			(at 0 0 0)
			(layer "F.SilkS")
			(hide yes)
			(effects
				(font
					(size 1.27 1.27)
				)
			)
		)
		(property "Value" ""
			(at 0 0 0)
			(layer "F.Fab")
			(effects
				(font
					(size 1.27 1.27)
				)
			)
		)
		(duplicate_pad_numbers_are_jumpers no)
		(fp_line
			(start -0.7874 -0.4064)
			(end 0.7874 -0.4064)
			(stroke
				(width 0.1524)
				(type default)
			)
			(layer "F.SilkS")
		)
		(fp_line
			(start -0.7874 0.4064)
			(end -0.7874 -0.4064)
			(stroke
				(width 0.1524)
				(type default)
			)
			(layer "F.SilkS")
		)
		(fp_line
			(start 0.7874 -0.4064)
			(end 0.7874 0.4064)
			(stroke
				(width 0.1524)
				(type default)
			)
			(layer "F.SilkS")
		)
		(fp_line
			(start 0.7874 0.4064)
			(end -0.7874 0.4064)
			(stroke
				(width 0.1524)
				(type default)
			)
			(layer "F.SilkS")
		)
		(fp_line
			(start -0.67945 -0.305054)
			(end -0.12065 -0.305054)
			(stroke
				(width 0.1)
				(type default)
			)
			(layer "F.Fab")
		)
		(fp_line
			(start -0.67945 0.3048)
			(end -0.67945 -0.305054)
			(stroke
				(width 0.1)
				(type default)
			)
			(layer "F.Fab")
		)
		(fp_line
			(start -0.12065 -0.305054)
			(end -0.12065 -0.2794)
			(stroke
				(width 0.1)
				(type default)
			)
			(layer "F.Fab")
		)
		(fp_line
			(start -0.12065 -0.2794)
			(end 0.12065 -0.2794)
			(stroke
				(width 0.1)
				(type default)
			)
			(layer "F.Fab")
		)
		(fp_line
			(start -0.12065 0.2794)
			(end -0.12065 0.3048)
			(stroke
				(width 0.1)
				(type default)
			)
			(layer "F.Fab")
		)
		(fp_line
			(start -0.12065 0.3048)
			(end -0.67945 0.3048)
			(stroke
				(width 0.1)
				(type default)
			)
			(layer "F.Fab")
		)
		(fp_line
			(start 0.120396 0.2794)
			(end -0.12065 0.2794)
			(stroke
				(width 0.1)
				(type default)
			)
			(layer "F.Fab")
		)
		(fp_line
			(start 0.120396 0.3048)
			(end 0.120396 0.2794)
			(stroke
				(width 0.1)
				(type default)
			)
			(layer "F.Fab")
		)
		(fp_line
			(start 0.12065 -0.3048)
			(end 0.67945 -0.3048)
			(stroke
				(width 0.1)
				(type default)
			)
			(layer "F.Fab")
		)
		(fp_line
			(start 0.12065 -0.2794)
			(end 0.12065 -0.3048)
			(stroke
				(width 0.1)
				(type default)
			)
			(layer "F.Fab")
		)
		(fp_line
			(start 0.67945 -0.3048)
			(end 0.67945 0.3048)
			(stroke
				(width 0.1)
				(type default)
			)
			(layer "F.Fab")
		)
		(fp_line
			(start 0.67945 0.3048)
			(end 0.120396 0.3048)
			(stroke
				(width 0.1)
				(type default)
			)
			(layer "F.Fab")
		)
		(pad "1" smd circle
			(at -0.40005 0)
			(size 0 0)
			(layers "F.Cu" "F.Mask" "F.Paste")
			(net "GND")
		)
		(pad "2" smd circle
			(at 0.40005 0)
			(size 0 0)
			(layers "F.Cu" "F.Mask" "F.Paste")
			(net "RST_MB_PERST_0_N")
		)
	)
	(footprint ""
		(layer "F.Cu")
		(at 338.263484 -343.952322 90)
		(property "Reference" "C574"
			(at 0 0 90)
			(layer "F.SilkS")
			(hide yes)
			(effects
				(font
					(size 1.27 1.27)
				)
			)
		)
		(property "Value" ""
			(at 0 0 90)
			(layer "F.Fab")
			(effects
				(font
					(size 1.27 1.27)
				)
			)
		)
		(duplicate_pad_numbers_are_jumpers no)
		(fp_line
			(start 0.299974 -0.150114)
			(end 0.299974 0.150114)
			(stroke
				(width 0.1)
				(type default)
			)
			(layer "F.Fab")
		)
		(fp_line
			(start -0.299974 -0.150114)
			(end 0.299974 -0.150114)
			(stroke
				(width 0.1)
				(type default)
			)
			(layer "F.Fab")
		)
		(fp_line
			(start 0.299974 0.150114)
			(end -0.299974 0.150114)
			(stroke
				(width 0.1)
				(type default)
			)
			(layer "F.Fab")
		)
		(fp_line
			(start -0.299974 0.150114)
			(end -0.299974 -0.150114)
			(stroke
				(width 0.1)
				(type default)
			)
			(layer "F.Fab")
		)
		(pad "1" smd rect
			(at -0.2667 0 90)
			(size 0.3048 0.381)
			(layers "F.Cu" "F.Mask" "F.Paste")
			(net "P5E_PEX2_STN6_TX_DN<100>")
		)
		(pad "2" smd rect
			(at 0.2667 0 90)
			(size 0.3048 0.381)
			(layers "F.Cu" "F.Mask" "F.Paste")
			(net "P5E_PEX2_STN6_TX_C_DN<100>")
		)
	)
	(footprint ""
		(layer "F.Cu")
		(at 292.310312 -63.652146 180)
		(property "Reference" "R6006"
			(at 0 0 180)
			(layer "F.SilkS")
			(hide yes)
			(effects
				(font
					(size 1.27 1.27)
				)
			)
		)
		(property "Value" ""
			(at 0 0 180)
			(layer "F.Fab")
			(effects
				(font
					(size 1.27 1.27)
				)
			)
		)
		(duplicate_pad_numbers_are_jumpers no)
		(fp_line
			(start 0.7874 0.4064)
			(end -0.7874 0.4064)
			(stroke
				(width 0.1524)
				(type default)
			)
			(layer "F.SilkS")
		)
		(fp_line
			(start 0.7874 -0.4064)
			(end 0.7874 0.4064)
			(stroke
				(width 0.1524)
				(type default)
			)
			(layer "F.SilkS")
		)
		(fp_line
			(start -0.7874 0.4064)
			(end -0.7874 -0.4064)
			(stroke
				(width 0.1524)
				(type default)
			)
			(layer "F.SilkS")
		)
		(fp_line
			(start -0.7874 -0.4064)
			(end 0.7874 -0.4064)
			(stroke
				(width 0.1524)
				(type default)
			)
			(layer "F.SilkS")
		)
		(fp_line
			(start 0.67945 0.3048)
			(end 0.120396 0.3048)
			(stroke
				(width 0.1)
				(type default)
			)
			(layer "F.Fab")
		)
		(fp_line
			(start 0.67945 -0.3048)
			(end 0.67945 0.3048)
			(stroke
				(width 0.1)
				(type default)
			)
			(layer "F.Fab")
		)
		(fp_line
			(start 0.12065 -0.2794)
			(end 0.12065 -0.3048)
			(stroke
				(width 0.1)
				(type default)
			)
			(layer "F.Fab")
		)
		(fp_line
			(start 0.12065 -0.3048)
			(end 0.67945 -0.3048)
			(stroke
				(width 0.1)
				(type default)
			)
			(layer "F.Fab")
		)
		(fp_line
			(start 0.120396 0.3048)
			(end 0.120396 0.2794)
			(stroke
				(width 0.1)
				(type default)
			)
			(layer "F.Fab")
		)
		(fp_line
			(start 0.120396 0.2794)
			(end -0.12065 0.2794)
			(stroke
				(width 0.1)
				(type default)
			)
			(layer "F.Fab")
		)
		(fp_line
			(start -0.12065 0.3048)
			(end -0.67945 0.3048)
			(stroke
				(width 0.1)
				(type default)
			)
			(layer "F.Fab")
		)
		(fp_line
			(start -0.12065 0.2794)
			(end -0.12065 0.3048)
			(stroke
				(width 0.1)
				(type default)
			)
			(layer "F.Fab")
		)
		(fp_line
			(start -0.12065 -0.2794)
			(end 0.12065 -0.2794)
			(stroke
				(width 0.1)
				(type default)
			)
			(layer "F.Fab")
		)
		(fp_line
			(start -0.12065 -0.305054)
			(end -0.12065 -0.2794)
			(stroke
				(width 0.1)
				(type default)
			)
			(layer "F.Fab")
		)
		(fp_line
			(start -0.67945 0.3048)
			(end -0.67945 -0.305054)
			(stroke
				(width 0.1)
				(type default)
			)
			(layer "F.Fab")
		)
		(fp_line
			(start -0.67945 -0.305054)
			(end -0.12065 -0.305054)
			(stroke
				(width 0.1)
				(type default)
			)
			(layer "F.Fab")
		)
		(pad "1" smd circle
			(at -0.40005 0 180)
			(size 0 0)
			(layers "F.Cu" "F.Mask" "F.Paste")
			(net "P5V_AUX")
		)
		(pad "2" smd circle
			(at 0.40005 0 180)
			(size 0 0)
			(layers "F.Cu" "F.Mask" "F.Paste")
			(net "P12V_SSD10_PG_G2")
		)
	)
	(footprint ""
		(layer "F.Cu")
		(at 444.7286 -230.2256 90)
		(property "Reference" "C4440"
			(at 0 0 90)
			(layer "F.SilkS")
			(hide yes)
			(effects
				(font
					(size 1.27 1.27)
				)
			)
		)
		(property "Value" ""
			(at 0 0 90)
			(layer "F.Fab")
			(effects
				(font
					(size 1.27 1.27)
				)
			)
		)
		(duplicate_pad_numbers_are_jumpers no)
		(fp_line
			(start 0.7874 -0.4064)
			(end 0.7874 0.4064)
			(stroke
				(width 0.1524)
				(type default)
			)
			(layer "F.SilkS")
		)
		(fp_line
			(start -0.7874 -0.4064)
			(end 0.7874 -0.4064)
			(stroke
				(width 0.1524)
				(type default)
			)
			(layer "F.SilkS")
		)
		(fp_line
			(start 0.7874 0.4064)
			(end -0.7874 0.4064)
			(stroke
				(width 0.1524)
				(type default)
			)
			(layer "F.SilkS")
		)
		(fp_line
			(start -0.7874 0.4064)
			(end -0.7874 -0.4064)
			(stroke
				(width 0.1524)
				(type default)
			)
			(layer "F.SilkS")
		)
		(fp_line
			(start -0.12065 -0.305054)
			(end -0.12065 -0.2794)
			(stroke
				(width 0.1)
				(type default)
			)
			(layer "F.Fab")
		)
		(fp_line
			(start -0.67945 -0.305054)
			(end -0.12065 -0.305054)
			(stroke
				(width 0.1)
				(type default)
			)
			(layer "F.Fab")
		)
		(fp_line
			(start 0.67945 -0.3048)
			(end 0.67945 0.3048)
			(stroke
				(width 0.1)
				(type default)
			)
			(layer "F.Fab")
		)
		(fp_line
			(start 0.12065 -0.3048)
			(end 0.67945 -0.3048)
			(stroke
				(width 0.1)
				(type default)
			)
			(layer "F.Fab")
		)
		(fp_line
			(start 0.12065 -0.2794)
			(end 0.12065 -0.3048)
			(stroke
				(width 0.1)
				(type default)
			)
			(layer "F.Fab")
		)
		(fp_line
			(start -0.12065 -0.2794)
			(end 0.12065 -0.2794)
			(stroke
				(width 0.1)
				(type default)
			)
			(layer "F.Fab")
		)
		(fp_line
			(start 0.120396 0.2794)
			(end -0.12065 0.2794)
			(stroke
				(width 0.1)
				(type default)
			)
			(layer "F.Fab")
		)
		(fp_line
			(start -0.12065 0.2794)
			(end -0.12065 0.3048)
			(stroke
				(width 0.1)
				(type default)
			)
			(layer "F.Fab")
		)
		(fp_line
			(start 0.67945 0.3048)
			(end 0.120396 0.3048)
			(stroke
				(width 0.1)
				(type default)
			)
			(layer "F.Fab")
		)
		(fp_line
			(start 0.120396 0.3048)
			(end 0.120396 0.2794)
			(stroke
				(width 0.1)
				(type default)
			)
			(layer "F.Fab")
		)
		(fp_line
			(start -0.12065 0.3048)
			(end -0.67945 0.3048)
			(stroke
				(width 0.1)
				(type default)
			)
			(layer "F.Fab")
		)
		(fp_line
			(start -0.67945 0.3048)
			(end -0.67945 -0.305054)
			(stroke
				(width 0.1)
				(type default)
			)
			(layer "F.Fab")
		)
		(pad "1" smd circle
			(at -0.40005 0 90)
			(size 0 0)
			(layers "F.Cu" "F.Mask" "F.Paste")
			(net "P3V3_AUX")
		)
		(pad "2" smd circle
			(at 0.40005 0 90)
			(size 0 0)
			(layers "F.Cu" "F.Mask" "F.Paste")
			(net "GND")
		)
	)
)
